# BASEBOARD_FAB2 (Tioga Pass) — schematic netlist excerpt (pin names and nets, part order shuffled) for the footprints in the layout excerpt that follows; sources: Cadence DE-HDL packaged netlist, KiCad conversion of Wiwynn_Tioga_Pass_MB.brd

C2A5  CAP_A  47UF 4V 20% X5R  pkg 0603V  page 228 : A = PVDDQ_KLM ; B = GND
DS9A4  LED  IC  pkg A1LF  page 158 : A = FM_UARTSW_LSB_R_N ; C = FM_UARTSW_LSB_N

(kicad_pcb
	(version 20260206)
	(generator "pcbnew")
	(generator_version "10.0")
	(general
		(thickness 1.6)
		(legacy_teardrops no)
	)
	(paper "A4")
	(title_block
		(title "Wiwynn_Tioga_Pass_MB.brd")
		(comment 1 "Tioga Pass / footprints 1645-1646 of 4770")
	)
	(layers
		(0 "F.Cu" signal "TOP")
		(4 "In1.Cu" signal "L2GND")
		(6 "In2.Cu" signal "L3")
		(8 "In3.Cu" signal "L4GND")
		(10 "In4.Cu" signal "L5")
		(12 "In5.Cu" signal "L6GND")
		(14 "In6.Cu" signal "L7VCC")
		(16 "In7.Cu" signal "L8VCC")
		(18 "In8.Cu" signal "L9GND")
		(20 "In9.Cu" signal "L10")
		(22 "In10.Cu" signal "L11GND")
		(24 "In11.Cu" signal "L12")
		(26 "In12.Cu" signal "L13GND")
		(2 "B.Cu" signal "BOTTOM")
		(9 "F.Adhes" user "F.Adhesive")
		(11 "B.Adhes" user "B.Adhesive")
		(13 "F.Paste" user "Package Geometry/Pastemask Top")
		(15 "B.Paste" user "Package Geometry/Pastemask Bottom")
		(5 "F.SilkS" user "Ref Des/Silkscreen Top")
		(7 "B.SilkS" user "Ref Des/Silkscreen Bottom")
		(1 "F.Mask" user "Board Geometry/Soldermask Top")
		(3 "B.Mask" user "Board Geometry/Soldermask Bottom")
		(17 "Dwgs.User" user "User.Drawings")
		(19 "Cmts.User" user "User.Comments")
		(21 "Eco1.User" user "User.Eco1")
		(23 "Eco2.User" user "User.Eco2")
		(25 "Edge.Cuts" user "Board Geometry/Outline")
		(27 "Margin" user)
		(31 "F.CrtYd" user "Package Geometry/Place Bound Top")
		(29 "B.CrtYd" user "Package Geometry/Place Bound Bottom")
		(35 "F.Fab" user "Ref Des/Assembly Top")
		(33 "B.Fab" user "Ref Des/Assembly Bottom")
	)
	(footprint ""
		(layer "F.Cu")
		(at 498.620034 -138.678666 90)
		(property "Reference" "DS9A4"
			(at -0.60071 0.94742 0)
			(unlocked yes)
			(layer "F.SilkS")
			(effects
				(font
					(size 0.7874 0.5842)
					(thickness 0.1524)
				)
			)
		)
		(property "Value" ""
			(at 0 0 90)
			(layer "F.Fab")
			(effects
				(font
					(size 1.27 1.27)
				)
			)
		)
		(duplicate_pad_numbers_are_jumpers no)
		(fp_line
			(start 0.992632 -1.34874)
			(end 0.992632 -0.437134)
			(stroke
				(width 0.1524)
				(type default)
			)
			(layer "F.SilkS")
		)
		(fp_line
			(start 1.473454 -0.437134)
			(end 0.992632 0.395732)
			(stroke
				(width 0.1524)
				(type default)
			)
			(layer "F.SilkS")
		)
		(fp_line
			(start 0.992632 -0.437134)
			(end 1.473454 -0.437134)
			(stroke
				(width 0.1524)
				(type default)
			)
			(layer "F.SilkS")
		)
		(fp_line
			(start 0.51181 -0.437134)
			(end 0.992632 -0.437134)
			(stroke
				(width 0.1524)
				(type default)
			)
			(layer "F.SilkS")
		)
		(fp_line
			(start 0.992632 0.395732)
			(end 0.51181 -0.437134)
			(stroke
				(width 0.1524)
				(type default)
			)
			(layer "F.SilkS")
		)
		(fp_line
			(start 0.51181 0.395732)
			(end 1.473454 0.395732)
			(stroke
				(width 0.1524)
				(type default)
			)
			(layer "F.SilkS")
		)
		(fp_line
			(start 0.992632 1.519174)
			(end 0.992632 0.395732)
			(stroke
				(width 0.1524)
				(type default)
			)
			(layer "F.SilkS")
		)
		(fp_rect
			(start -0.4064 1.6891)
			(end 0.4064 0.0889)
			(stroke
				(width 0)
				(type default)
			)
			(fill no)
			(layer "F.CrtYd")
		)
		(fp_line
			(start 1.473454 -0.437134)
			(end 0.992632 0.395732)
			(stroke
				(width 0.1)
				(type default)
			)
			(layer "F.Fab")
		)
		(fp_line
			(start 0.992632 -0.437134)
			(end 0.992632 -1.34874)
			(stroke
				(width 0.1)
				(type default)
			)
			(layer "F.Fab")
		)
		(fp_line
			(start 0.51181 -0.437134)
			(end 1.473454 -0.437134)
			(stroke
				(width 0.1)
				(type default)
			)
			(layer "F.Fab")
		)
		(fp_line
			(start 0.4064 0.0889)
			(end 0.4064 1.6891)
			(stroke
				(width 0.1)
				(type default)
			)
			(layer "F.Fab")
		)
		(fp_line
			(start -0.4064 0.0889)
			(end 0.4064 0.0889)
			(stroke
				(width 0.1)
				(type default)
			)
			(layer "F.Fab")
		)
		(fp_line
			(start 0.992632 0.395732)
			(end 0.51181 -0.437134)
			(stroke
				(width 0.1)
				(type default)
			)
			(layer "F.Fab")
		)
		(fp_line
			(start 0.992632 0.395732)
			(end 0.992632 1.519174)
			(stroke
				(width 0.1)
				(type default)
			)
			(layer "F.Fab")
		)
		(fp_line
			(start 0.51181 0.395732)
			(end 1.473454 0.395732)
			(stroke
				(width 0.1)
				(type default)
			)
			(layer "F.Fab")
		)
		(fp_line
			(start 0.4064 1.6891)
			(end -0.4064 1.6891)
			(stroke
				(width 0.1)
				(type default)
			)
			(layer "F.Fab")
		)
		(fp_line
			(start -0.4064 1.6891)
			(end -0.4064 0.0889)
			(stroke
				(width 0.1)
				(type default)
			)
			(layer "F.Fab")
		)
		(pad "1" smd rect
			(at 0 0 90)
			(size 0.762 1.27)
			(layers "F.Cu" "F.Mask" "F.Paste")
			(net "FM_UARTSW_LSB_R_N")
		)
		(pad "2" smd rect
			(at 0 1.778 90)
			(size 0.762 1.27)
			(layers "F.Cu" "F.Mask" "F.Paste")
			(net "FM_UARTSW_LSB_N")
		)
		(zone
			(layer "F.Cu")
			(hatch none 0.5)
			(connect_pads
				(clearance 0)
			)
			(min_thickness 0.25)
			(keepout
				(tracks not_allowed)
				(vias allowed)
				(pads allowed)
				(copperpour not_allowed)
				(footprints allowed)
			)
			(placement
				(enabled no)
				(sheetname "")
			)
			(fill
				(thermal_gap 0.5)
				(thermal_bridge_width 0.5)
				(island_removal_mode 0)
			)
			(polygon
				(pts
					(xy 499.280434 -138.297666) (xy 499.280434 -139.059666) (xy 499.737634 -139.059666) (xy 499.737634 -138.297666)
				)
			)
		)
		(zone
			(layer "F.Cu")
			(hatch none 0.5)
			(connect_pads
				(clearance 0)
			)
			(min_thickness 0.25)
			(keepout
				(tracks allowed)
				(vias not_allowed)
				(pads allowed)
				(copperpour not_allowed)
				(footprints allowed)
			)
			(placement
				(enabled no)
				(sheetname "")
			)
			(fill
				(thermal_gap 0.5)
				(thermal_bridge_width 0.5)
				(island_removal_mode 0)
			)
			(polygon
				(pts
					(xy 499.737634 -138.297666) (xy 499.737634 -139.059666) (xy 499.280434 -139.059666) (xy 499.280434 -138.297666)
				)
			)
		)
	)
	(footprint ""
		(layer "F.Cu")
		(at 92.911168 -149.8092 -90)
		(property "Reference" "C2A5"
			(at 0 0 270)
			(layer "F.SilkS")
			(hide yes)
			(effects
				(font
					(size 1.27 1.27)
				)
			)
		)
		(property "Value" ""
			(at 0 0 270)
			(layer "F.Fab")
			(effects
				(font
					(size 1.27 1.27)
				)
			)
		)
		(duplicate_pad_numbers_are_jumpers no)
		(fp_rect
			(start -0.500126 1.598422)
			(end 0.500126 -0.201422)
			(stroke
				(width 0)
				(type default)
			)
			(fill no)
			(layer "F.CrtYd")
		)
		(fp_line
			(start -0.500126 1.598422)
			(end -0.500126 -0.201422)
			(stroke
				(width 0.1)
				(type default)
			)
			(layer "F.Fab")
		)
		(fp_line
			(start 0.500126 1.598422)
			(end -0.500126 1.598422)
			(stroke
				(width 0.1)
				(type default)
			)
			(layer "F.Fab")
		)
		(fp_line
			(start -0.500126 -0.201422)
			(end 0.500126 -0.201422)
			(stroke
				(width 0.1)
				(type default)
			)
			(layer "F.Fab")
		)
		(fp_line
			(start 0.500126 -0.201422)
			(end 0.500126 1.598422)
			(stroke
				(width 0.1)
				(type default)
			)
			(layer "F.Fab")
		)
		(pad "1" smd rect
			(at 0 0 180)
			(size 0.889 0.9906)
			(layers "F.Cu" "F.Mask" "F.Paste")
			(net "PVDDQ_KLM")
		)
		(pad "2" smd rect
			(at 0 1.397 180)
			(size 0.889 0.9906)
			(layers "F.Cu" "F.Mask" "F.Paste")
			(net "GND")
		)
		(zone
			(layer "F.Cu")
			(hatch none 0.5)
			(connect_pads
				(clearance 0)
			)
			(min_thickness 0.25)
			(keepout
				(tracks allowed)
				(vias not_allowed)
				(pads allowed)
				(copperpour not_allowed)
				(footprints allowed)
			)
			(placement
				(enabled no)
				(sheetname "")
			)
			(fill
				(thermal_gap 0.5)
				(thermal_bridge_width 0.5)
				(island_removal_mode 0)
			)
			(polygon
				(pts
					(xy 91.958668 -150.3045) (xy 91.958668 -149.3139) (xy 92.466668 -149.3139) (xy 92.466668 -150.3045)
				)
			)
		)
		(zone
			(layer "F.Cu")
			(hatch none 0.5)
			(connect_pads
				(clearance 0)
			)
			(min_thickness 0.25)
			(keepout
				(tracks not_allowed)
				(vias allowed)
				(pads allowed)
				(copperpour not_allowed)
				(footprints allowed)
			)
			(placement
				(enabled no)
				(sheetname "")
			)
			(fill
				(thermal_gap 0.5)
				(thermal_bridge_width 0.5)
				(island_removal_mode 0)
			)
			(polygon
				(pts
					(xy 91.958668 -150.3045) (xy 91.958668 -149.3139) (xy 92.466668 -149.3139) (xy 92.466668 -150.3045)
				)
			)
		)
	)
)
